(kicad_pcb
	(version 20260206)
	(generator "pcbnew")
	(generator_version "10.0")
	(general
		(thickness 1.6)
		(legacy_teardrops no)
	)
	(paper "A4")
	(title_block
		(title "peb — Lightning_PEB_BRD.brd")
		(comment 1 "Lightning (Wiwynn / Facebook NVMe JBOF) / footprints 724-731 of 2563")
	)
	(layers
		(0 "F.Cu" signal "TOP")
		(4 "In1.Cu" signal "L2GND")
		(6 "In2.Cu" signal "L3")
		(8 "In3.Cu" signal "L4VCC")
		(10 "In4.Cu" signal "L5VCC")
		(12 "In5.Cu" signal "L6")
		(14 "In6.Cu" signal "L7GND")
		(2 "B.Cu" signal "BOTTOM")
		(9 "F.Adhes" user "F.Adhesive")
		(11 "B.Adhes" user "B.Adhesive")
		(13 "F.Paste" user "Package Geometry/Pastemask Top")
		(15 "B.Paste" user "Package Geometry/Pastemask Bottom")
		(5 "F.SilkS" user "Ref Des/Silkscreen Top")
		(7 "B.SilkS" user "Ref Des/Silkscreen Bottom")
		(1 "F.Mask" user "Board Geometry/Soldermask Top")
		(3 "B.Mask" user "Board Geometry/Soldermask Bottom")
		(17 "Dwgs.User" user "User.Drawings")
		(19 "Cmts.User" user "User.Comments")
		(21 "Eco1.User" user "User.Eco1")
		(23 "Eco2.User" user "User.Eco2")
		(25 "Edge.Cuts" user "Board Geometry/Outline")
		(27 "Margin" user)
		(31 "F.CrtYd" user "Package Geometry/Place Bound Top")
		(29 "B.CrtYd" user "Package Geometry/Place Bound Bottom")
		(35 "F.Fab" user "Ref Des/Assembly Top")
		(33 "B.Fab" user "Ref Des/Assembly Bottom")
	)
	(footprint ""
		(layer "F.Cu")
		(at 121.276364 -46.86808)
		(property "Reference" "R933"
			(at 0 0 0)
			(layer "F.SilkS")
			(hide yes)
			(effects
				(font
					(size 1.27 1.27)
				)
			)
		)
		(property "Value" "4K7R2F-GP"
			(at 0.064008 -3.993896 0)
			(unlocked yes)
			(layer "F.Fab")
			(hide yes)
			(effects
				(font
					(size 1.016 1.016)
					(thickness 0.1524)
				)
			)
		)
		(property "Device Type" "R402H16"
			(at 0.064008 -5.517896 0)
			(unlocked yes)
			(layer "F.Fab")
			(hide yes)
			(effects
				(font
					(size 1.016 1.016)
					(thickness 0.1524)
				)
			)
		)
		(duplicate_pad_numbers_are_jumpers no)
		(fp_line
			(start -0.508 -0.9398)
			(end -0.508 0.9398)
			(stroke
				(width 0.1524)
				(type default)
			)
			(layer "F.SilkS")
		)
		(fp_line
			(start 0.508 -0.9398)
			(end -0.508 -0.9398)
			(stroke
				(width 0.1524)
				(type default)
			)
			(layer "F.SilkS")
		)
		(fp_rect
			(start -0.508 0.9398)
			(end 0.508 -0.9398)
			(stroke
				(width 0)
				(type default)
			)
			(fill no)
			(layer "F.CrtYd")
		)
		(fp_rect
			(start -0.508 0.9398)
			(end 0.508 -0.9398)
			(stroke
				(width 0)
				(type default)
			)
			(fill no)
			(layer "F.Fab")
		)
		(pad "1" smd custom
			(at 0 -0.4445)
			(size 0.1397 0.1397)
			(layers "F.Cu" "F.Mask" "F.Paste")
			(net "P3V3_STBY")
			(options
				(clearance outline)
				(anchor circle)
			)
			(primitives
				(gr_poly
					(pts
						(arc
							(start -0.1778 -0.2794)
							(mid -0.249642 -0.249642)
							(end -0.2794 -0.1778)
						)
						(arc
							(start -0.2794 0.1778)
							(mid -0.249642 0.249642)
							(end -0.1778 0.2794)
						)
						(arc
							(start 0.1778 0.2794)
							(mid 0.249642 0.249642)
							(end 0.2794 0.1778)
						)
						(arc
							(start 0.2794 -0.1778)
							(mid 0.249642 -0.249642)
							(end 0.1778 -0.2794)
						)
					)
					(width 0)
					(fill yes)
				)
			)
		)
		(pad "2" smd custom
			(at 0 0.4445)
			(size 0.1397 0.1397)
			(layers "F.Cu" "F.Mask" "F.Paste")
			(net "BMC_ADD2_PWR")
			(options
				(clearance outline)
				(anchor circle)
			)
			(primitives
				(gr_poly
					(pts
						(arc
							(start -0.1778 -0.2794)
							(mid -0.249642 -0.249642)
							(end -0.2794 -0.1778)
						)
						(arc
							(start -0.2794 0.1778)
							(mid -0.249642 0.249642)
							(end -0.1778 0.2794)
						)
						(arc
							(start 0.1778 0.2794)
							(mid 0.249642 0.249642)
							(end 0.2794 0.1778)
						)
						(arc
							(start 0.2794 -0.1778)
							(mid 0.249642 -0.249642)
							(end 0.1778 -0.2794)
						)
					)
					(width 0)
					(fill yes)
				)
			)
		)
	)
	(footprint ""
		(layer "F.Cu")
		(at 217.0176 -4.064)
		(property "Reference" "R665"
			(at 0 0 0)
			(layer "F.SilkS")
			(hide yes)
			(effects
				(font
					(size 1.27 1.27)
				)
			)
		)
		(property "Value" "4K7R2F-GP"
			(at 0.064008 -3.993896 0)
			(unlocked yes)
			(layer "F.Fab")
			(hide yes)
			(effects
				(font
					(size 1.016 1.016)
					(thickness 0.1524)
				)
			)
		)
		(property "Device Type" "R402H16"
			(at 0.064008 -5.517896 0)
			(unlocked yes)
			(layer "F.Fab")
			(hide yes)
			(effects
				(font
					(size 1.016 1.016)
					(thickness 0.1524)
				)
			)
		)
		(duplicate_pad_numbers_are_jumpers no)
		(fp_line
			(start -0.508 -0.9398)
			(end -0.508 0.9398)
			(stroke
				(width 0.1524)
				(type default)
			)
			(layer "F.SilkS")
		)
		(fp_line
			(start 0.508 -0.9398)
			(end -0.508 -0.9398)
			(stroke
				(width 0.1524)
				(type default)
			)
			(layer "F.SilkS")
		)
		(fp_rect
			(start -0.508 0.9398)
			(end 0.508 -0.9398)
			(stroke
				(width 0)
				(type default)
			)
			(fill no)
			(layer "F.CrtYd")
		)
		(fp_rect
			(start -0.508 0.9398)
			(end 0.508 -0.9398)
			(stroke
				(width 0)
				(type default)
			)
			(fill no)
			(layer "F.Fab")
		)
		(pad "1" smd custom
			(at 0 -0.4445)
			(size 0.1397 0.1397)
			(layers "F.Cu" "F.Mask" "F.Paste")
			(net "Q3202_D")
			(options
				(clearance outline)
				(anchor circle)
			)
			(primitives
				(gr_poly
					(pts
						(arc
							(start -0.1778 -0.2794)
							(mid -0.249642 -0.249642)
							(end -0.2794 -0.1778)
						)
						(arc
							(start -0.2794 0.1778)
							(mid -0.249642 0.249642)
							(end -0.1778 0.2794)
						)
						(arc
							(start 0.1778 0.2794)
							(mid 0.249642 0.249642)
							(end 0.2794 0.1778)
						)
						(arc
							(start 0.2794 -0.1778)
							(mid 0.249642 -0.249642)
							(end 0.1778 -0.2794)
						)
					)
					(width 0)
					(fill yes)
				)
			)
		)
		(pad "2" smd custom
			(at 0 0.4445)
			(size 0.1397 0.1397)
			(layers "F.Cu" "F.Mask" "F.Paste")
			(net "DUT_VDDO")
			(options
				(clearance outline)
				(anchor circle)
			)
			(primitives
				(gr_poly
					(pts
						(arc
							(start -0.1778 -0.2794)
							(mid -0.249642 -0.249642)
							(end -0.2794 -0.1778)
						)
						(arc
							(start -0.2794 0.1778)
							(mid -0.249642 0.249642)
							(end -0.1778 0.2794)
						)
						(arc
							(start 0.1778 0.2794)
							(mid 0.249642 0.249642)
							(end 0.2794 0.1778)
						)
						(arc
							(start 0.2794 -0.1778)
							(mid 0.249642 -0.249642)
							(end 0.1778 -0.2794)
						)
					)
					(width 0)
					(fill yes)
				)
			)
		)
	)
	(footprint ""
		(layer "F.Cu")
		(at 184.785 -71.628 180)
		(property "Reference" "C552"
			(at 0 0 180)
			(layer "F.SilkS")
			(hide yes)
			(effects
				(font
					(size 1.27 1.27)
				)
			)
		)
		(property "Value" "SC4D7U16V5KX-1-GP"
			(at -0.0762 -6.1214 180)
			(unlocked yes)
			(layer "F.Fab")
			(hide yes)
			(effects
				(font
					(size 1.016 1.016)
					(thickness 0.1524)
				)
			)
		)
		(property "Device Type" "C805H56"
			(at -0.0762 -8.1534 180)
			(unlocked yes)
			(layer "F.Fab")
			(hide yes)
			(effects
				(font
					(size 1.016 1.016)
					(thickness 0.1524)
				)
			)
		)
		(duplicate_pad_numbers_are_jumpers no)
		(fp_line
			(start 0.635 0)
			(end -0.635 0)
			(stroke
				(width 0.508)
				(type default)
			)
			(layer "F.SilkS")
		)
		(fp_rect
			(start -0.9652 1.778)
			(end 0.9652 -1.778)
			(stroke
				(width 0)
				(type default)
			)
			(fill no)
			(layer "F.CrtYd")
		)
		(fp_poly
			(pts
				(xy -0.9652 -1.778) (xy 0.9652 -1.778) (xy 0.9652 1.778) (xy -0.9652 1.778)
			)
			(stroke
				(width 0)
				(type default)
			)
			(fill no)
			(layer "F.Fab")
		)
		(pad "1" smd rect
			(at 0 -0.9652 180)
			(size 1.397 1.143)
			(layers "F.Cu" "F.Mask" "F.Paste")
			(net "DUT_AVD_PCIE")
		)
		(pad "2" smd rect
			(at 0 0.9652 180)
			(size 1.397 1.143)
			(layers "F.Cu" "F.Mask" "F.Paste")
			(net "GND")
		)
	)
	(footprint ""
		(layer "F.Cu")
		(at 32.3596 -103.2764 180)
		(property "Reference" "R695"
			(at 0 0 180)
			(layer "F.SilkS")
			(hide yes)
			(effects
				(font
					(size 1.27 1.27)
				)
			)
		)
		(property "Value" "4K7R2F-GP"
			(at 0.064008 -3.993896 180)
			(unlocked yes)
			(layer "F.Fab")
			(hide yes)
			(effects
				(font
					(size 1.016 1.016)
					(thickness 0.1524)
				)
			)
		)
		(property "Device Type" "R402H16"
			(at 0.064008 -5.517896 180)
			(unlocked yes)
			(layer "F.Fab")
			(hide yes)
			(effects
				(font
					(size 1.016 1.016)
					(thickness 0.1524)
				)
			)
		)
		(duplicate_pad_numbers_are_jumpers no)
		(fp_line
			(start 0.508 -0.9398)
			(end -0.508 -0.9398)
			(stroke
				(width 0.1524)
				(type default)
			)
			(layer "F.SilkS")
		)
		(fp_line
			(start -0.508 -0.9398)
			(end -0.508 0.9398)
			(stroke
				(width 0.1524)
				(type default)
			)
			(layer "F.SilkS")
		)
		(fp_rect
			(start -0.508 0.9398)
			(end 0.508 -0.9398)
			(stroke
				(width 0)
				(type default)
			)
			(fill no)
			(layer "F.CrtYd")
		)
		(fp_rect
			(start -0.508 0.9398)
			(end 0.508 -0.9398)
			(stroke
				(width 0)
				(type default)
			)
			(fill no)
			(layer "F.Fab")
		)
		(pad "1" smd custom
			(at 0 -0.4445 180)
			(size 0.1397 0.1397)
			(layers "F.Cu" "F.Mask" "F.Paste")
			(net "SPICS0_N")
			(options
				(clearance outline)
				(anchor circle)
			)
			(primitives
				(gr_poly
					(pts
						(arc
							(start -0.1778 -0.2794)
							(mid -0.249642 -0.249642)
							(end -0.2794 -0.1778)
						)
						(arc
							(start -0.2794 0.1778)
							(mid -0.249642 0.249642)
							(end -0.1778 0.2794)
						)
						(arc
							(start 0.1778 0.2794)
							(mid 0.249642 0.249642)
							(end 0.2794 0.1778)
						)
						(arc
							(start 0.2794 -0.1778)
							(mid 0.249642 -0.249642)
							(end 0.1778 -0.2794)
						)
					)
					(width 0)
					(fill yes)
				)
			)
		)
		(pad "2" smd custom
			(at 0 0.4445 180)
			(size 0.1397 0.1397)
			(layers "F.Cu" "F.Mask" "F.Paste")
			(net "P3V3_STBY")
			(options
				(clearance outline)
				(anchor circle)
			)
			(primitives
				(gr_poly
					(pts
						(arc
							(start -0.1778 -0.2794)
							(mid -0.249642 -0.249642)
							(end -0.2794 -0.1778)
						)
						(arc
							(start -0.2794 0.1778)
							(mid -0.249642 0.249642)
							(end -0.1778 0.2794)
						)
						(arc
							(start 0.1778 0.2794)
							(mid 0.249642 0.249642)
							(end 0.2794 0.1778)
						)
						(arc
							(start 0.2794 -0.1778)
							(mid 0.249642 -0.249642)
							(end 0.1778 -0.2794)
						)
					)
					(width 0)
					(fill yes)
				)
			)
		)
	)
	(footprint ""
		(layer "F.Cu")
		(at 133.891274 -59.73572 180)
		(property "Reference" "R955"
			(at 0 0 180)
			(layer "F.SilkS")
			(hide yes)
			(effects
				(font
					(size 1.27 1.27)
				)
			)
		)
		(property "Value" "33R2J-2-GP"
			(at 0.064008 -3.993896 180)
			(unlocked yes)
			(layer "F.Fab")
			(hide yes)
			(effects
				(font
					(size 1.016 1.016)
					(thickness 0.1524)
				)
			)
		)
		(property "Device Type" "R402H16"
			(at 0.064008 -5.517896 180)
			(unlocked yes)
			(layer "F.Fab")
			(hide yes)
			(effects
				(font
					(size 1.016 1.016)
					(thickness 0.1524)
				)
			)
		)
		(duplicate_pad_numbers_are_jumpers no)
		(fp_line
			(start 0.508 -0.9398)
			(end -0.508 -0.9398)
			(stroke
				(width 0.1524)
				(type default)
			)
			(layer "F.SilkS")
		)
		(fp_line
			(start -0.508 -0.9398)
			(end -0.508 0.9398)
			(stroke
				(width 0.1524)
				(type default)
			)
			(layer "F.SilkS")
		)
		(fp_rect
			(start -0.508 0.9398)
			(end 0.508 -0.9398)
			(stroke
				(width 0)
				(type default)
			)
			(fill no)
			(layer "F.CrtYd")
		)
		(fp_rect
			(start -0.508 0.9398)
			(end 0.508 -0.9398)
			(stroke
				(width 0)
				(type default)
			)
			(fill no)
			(layer "F.Fab")
		)
		(pad "1" smd custom
			(at 0 -0.4445 180)
			(size 0.1397 0.1397)
			(layers "F.Cu" "F.Mask" "F.Paste")
			(net "SPI_DATA0_1")
			(options
				(clearance outline)
				(anchor circle)
			)
			(primitives
				(gr_poly
					(pts
						(arc
							(start -0.1778 -0.2794)
							(mid -0.249642 -0.249642)
							(end -0.2794 -0.1778)
						)
						(arc
							(start -0.2794 0.1778)
							(mid -0.249642 0.249642)
							(end -0.1778 0.2794)
						)
						(arc
							(start 0.1778 0.2794)
							(mid 0.249642 0.249642)
							(end 0.2794 0.1778)
						)
						(arc
							(start 0.2794 -0.1778)
							(mid 0.249642 -0.249642)
							(end 0.1778 -0.2794)
						)
					)
					(width 0)
					(fill yes)
				)
			)
		)
		(pad "2" smd custom
			(at 0 0.4445 180)
			(size 0.1397 0.1397)
			(layers "F.Cu" "F.Mask" "F.Paste")
			(net "SPI_DATA0_1_R")
			(options
				(clearance outline)
				(anchor circle)
			)
			(primitives
				(gr_poly
					(pts
						(arc
							(start -0.1778 -0.2794)
							(mid -0.249642 -0.249642)
							(end -0.2794 -0.1778)
						)
						(arc
							(start -0.2794 0.1778)
							(mid -0.249642 0.249642)
							(end -0.1778 0.2794)
						)
						(arc
							(start 0.1778 0.2794)
							(mid 0.249642 0.249642)
							(end 0.2794 0.1778)
						)
						(arc
							(start 0.2794 -0.1778)
							(mid 0.249642 -0.249642)
							(end 0.1778 -0.2794)
						)
					)
					(width 0)
					(fill yes)
				)
			)
		)
	)
	(footprint ""
		(layer "F.Cu")
		(at 27.686 -143.637 -90)
		(property "Reference" "R450"
			(at 0 0 270)
			(layer "F.SilkS")
			(hide yes)
			(effects
				(font
					(size 1.27 1.27)
				)
			)
		)
		(property "Value" "0R2J-2-GP"
			(at 0.064008 -3.993896 270)
			(unlocked yes)
			(layer "F.Fab")
			(hide yes)
			(effects
				(font
					(size 1.016 1.016)
					(thickness 0.1524)
				)
			)
		)
		(property "Device Type" "R402H16"
			(at 0.064008 -5.517896 270)
			(unlocked yes)
			(layer "F.Fab")
			(hide yes)
			(effects
				(font
					(size 1.016 1.016)
					(thickness 0.1524)
				)
			)
		)
		(duplicate_pad_numbers_are_jumpers no)
		(fp_line
			(start -0.508 -0.9398)
			(end -0.508 0.9398)
			(stroke
				(width 0.1524)
				(type default)
			)
			(layer "F.SilkS")
		)
		(fp_line
			(start 0.508 -0.9398)
			(end -0.508 -0.9398)
			(stroke
				(width 0.1524)
				(type default)
			)
			(layer "F.SilkS")
		)
		(fp_rect
			(start -0.508 0.9398)
			(end 0.508 -0.9398)
			(stroke
				(width 0)
				(type default)
			)
			(fill no)
			(layer "F.CrtYd")
		)
		(fp_rect
			(start -0.508 0.9398)
			(end 0.508 -0.9398)
			(stroke
				(width 0)
				(type default)
			)
			(fill no)
			(layer "F.Fab")
		)
		(pad "1" smd custom
			(at 0 -0.4445 270)
			(size 0.1397 0.1397)
			(layers "F.Cu" "F.Mask" "F.Paste")
			(net "BMC_USB2_HDN")
			(options
				(clearance outline)
				(anchor circle)
			)
			(primitives
				(gr_poly
					(pts
						(arc
							(start -0.1778 -0.2794)
							(mid -0.249642 -0.249642)
							(end -0.2794 -0.1778)
						)
						(arc
							(start -0.2794 0.1778)
							(mid -0.249642 0.249642)
							(end -0.1778 0.2794)
						)
						(arc
							(start 0.1778 0.2794)
							(mid 0.249642 0.249642)
							(end 0.2794 0.1778)
						)
						(arc
							(start 0.2794 -0.1778)
							(mid 0.249642 -0.249642)
							(end 0.1778 -0.2794)
						)
					)
					(width 0)
					(fill yes)
				)
			)
		)
		(pad "2" smd custom
			(at 0 0.4445 270)
			(size 0.1397 0.1397)
			(layers "F.Cu" "F.Mask" "F.Paste")
			(net "USB2_BMC_DN")
			(options
				(clearance outline)
				(anchor circle)
			)
			(primitives
				(gr_poly
					(pts
						(arc
							(start -0.1778 -0.2794)
							(mid -0.249642 -0.249642)
							(end -0.2794 -0.1778)
						)
						(arc
							(start -0.2794 0.1778)
							(mid -0.249642 0.249642)
							(end -0.1778 0.2794)
						)
						(arc
							(start 0.1778 0.2794)
							(mid 0.249642 0.249642)
							(end 0.2794 0.1778)
						)
						(arc
							(start 0.2794 -0.1778)
							(mid 0.249642 -0.249642)
							(end 0.1778 -0.2794)
						)
					)
					(width 0)
					(fill yes)
				)
			)
		)
	)
	(footprint ""
		(layer "F.Cu")
		(at 137.69848 -55.06847 180)
		(property "Reference" "SC1307"
			(at 0 0 180)
			(layer "F.SilkS")
			(hide yes)
			(effects
				(font
					(size 1.27 1.27)
				)
			)
		)
		(property "Value" "SCD1U16V2KX-3GP"
			(at 1.1811 -2.7051 180)
			(unlocked yes)
			(layer "F.Fab")
			(hide yes)
			(effects
				(font
					(size 1.016 1.016)
					(thickness 0.1524)
				)
			)
		)
		(property "Device Type" "C402H22"
			(at 1.1811 -4.2291 180)
			(unlocked yes)
			(layer "F.Fab")
			(hide yes)
			(effects
				(font
					(size 1.016 1.016)
					(thickness 0.1524)
				)
			)
		)
		(duplicate_pad_numbers_are_jumpers no)
		(fp_rect
			(start -0.4318 0.9525)
			(end 0.4318 -0.9525)
			(stroke
				(width 0)
				(type default)
			)
			(fill no)
			(layer "F.CrtYd")
		)
		(fp_rect
			(start -0.4318 0.9525)
			(end 0.4318 -0.9525)
			(stroke
				(width 0)
				(type default)
			)
			(fill no)
			(layer "F.Fab")
		)
		(pad "1" smd custom
			(at 0 -0.4445 180)
			(size 0.1524 0.1524)
			(layers "F.Cu" "F.Mask" "F.Paste")
			(net "P5V_STBY")
			(options
				(clearance outline)
				(anchor circle)
			)
			(primitives
				(gr_poly
					(pts
						(arc
							(start 0.3048 -0.2032)
							(mid 0.275042 -0.275042)
							(end 0.2032 -0.3048)
						)
						(arc
							(start -0.2032 -0.3048)
							(mid -0.275042 -0.275042)
							(end -0.3048 -0.2032)
						)
						(arc
							(start -0.3048 0.2032)
							(mid -0.275042 0.275042)
							(end -0.2032 0.3048)
						)
						(arc
							(start 0.2032 0.3048)
							(mid 0.275042 0.275042)
							(end 0.3048 0.2032)
						)
					)
					(width 0)
					(fill yes)
				)
			)
		)
		(pad "2" smd custom
			(at 0 0.4445 180)
			(size 0.1524 0.1524)
			(layers "F.Cu" "F.Mask" "F.Paste")
			(net "GND")
			(options
				(clearance outline)
				(anchor circle)
			)
			(primitives
				(gr_poly
					(pts
						(arc
							(start 0.3048 -0.2032)
							(mid 0.275042 -0.275042)
							(end 0.2032 -0.3048)
						)
						(arc
							(start -0.2032 -0.3048)
							(mid -0.275042 -0.275042)
							(end -0.3048 -0.2032)
						)
						(arc
							(start -0.3048 0.2032)
							(mid -0.275042 0.275042)
							(end -0.2032 0.3048)
						)
						(arc
							(start 0.2032 0.3048)
							(mid 0.275042 0.275042)
							(end 0.3048 0.2032)
						)
					)
					(width 0)
					(fill yes)
				)
			)
		)
	)
	(footprint ""
		(layer "F.Cu")
		(at 88.9 -45.974)
		(property "Reference" "PG4"
			(at 0 0 0)
			(layer "F.SilkS")
			(hide yes)
			(effects
				(font
					(size 1.27 1.27)
				)
			)
		)
		(property "Value" "GAP-CLOSE-PWR-3-GP"
			(at 0.0254 -6.5786 0)
			(unlocked yes)
			(layer "F.Fab")
			(hide yes)
			(effects
				(font
					(size 1.016 1.016)
					(thickness 0.1524)
				)
			)
		)
		(property "Device Type" "GAP-CLOSE-PWR-3"
			(at 0.0254 -8.255 0)
			(unlocked yes)
			(layer "F.Fab")
			(hide yes)
			(effects
				(font
					(size 1.016 1.016)
					(thickness 0.1524)
				)
			)
		)
		(duplicate_pad_numbers_are_jumpers no)
		(fp_rect
			(start -0.7112 0.4572)
			(end 0.7112 -0.4572)
			(stroke
				(width 0)
				(type default)
			)
			(fill no)
			(layer "F.CrtYd")
		)
		(fp_poly
			(pts
				(xy -0.7112 -0.4572) (xy 0.7112 -0.4572) (xy 0.7112 0.4572) (xy -0.7112 0.4572)
			)
			(stroke
				(width 0)
				(type default)
			)
			(fill no)
			(layer "F.Fab")
		)
		(pad "1" smd rect
			(at -0.3048 0)
			(size 0.6604 0.762)
			(layers "F.Cu" "F.Mask" "F.Paste")
			(net "P3V3_PWR")
		)
		(pad "2" smd rect
			(at 0.3048 0)
			(size 0.6604 0.762)
			(layers "F.Cu" "F.Mask" "F.Paste")
			(net "P3V3_STBY")
		)
	)
)
